(kicad_pcb
	(version 20260206)
	(generator "pcbnew")
	(generator_version "10.0")
	(general
		(thickness 1.6)
		(legacy_teardrops no)
	)
	(paper "A4")
	(title_block
		(title "04192023_DAF0TMB3IC0_F0TG_MB_C_brd_V02_OCP.brd")
		(comment 1 "Grand Teton / footprint 2783 of 8354 (U26), pads 652-759 of 6102")
	)
	(layers
		(0 "F.Cu" signal "TOP")
		(4 "In1.Cu" signal "GND")
		(6 "In2.Cu" signal "IN1")
		(8 "In3.Cu" signal "GND1")
		(10 "In4.Cu" signal "IN2")
		(12 "In5.Cu" signal "GND2")
		(14 "In6.Cu" signal "IN3")
		(16 "In7.Cu" signal "GND3")
		(18 "In8.Cu" signal "VCC")
		(20 "In9.Cu" signal "VCC1")
		(22 "In10.Cu" signal "GND4")
		(24 "In11.Cu" signal "IN4")
		(26 "In12.Cu" signal "GND5")
		(28 "In13.Cu" signal "IN5")
		(30 "In14.Cu" signal "GND6")
		(32 "In15.Cu" signal "IN6")
		(34 "In16.Cu" signal "GND7")
		(2 "B.Cu" signal "BOTTOM")
		(9 "F.Adhes" user "F.Adhesive")
		(11 "B.Adhes" user "B.Adhesive")
		(13 "F.Paste" user "Package Geometry/Pastemask Top")
		(15 "B.Paste" user "Package Geometry/Pastemask Bottom")
		(5 "F.SilkS" user "Ref Des/Silkscreen Top")
		(7 "B.SilkS" user "Ref Des/Silkscreen Bottom")
		(1 "F.Mask" user "Board Geometry/Soldermask Top")
		(3 "B.Mask" user "Board Geometry/Soldermask Bottom")
		(17 "Dwgs.User" user "User.Drawings")
		(19 "Cmts.User" user "User.Comments")
		(21 "Eco1.User" user "User.Eco1")
		(23 "Eco2.User" user "User.Eco2")
		(25 "Edge.Cuts" user "Board Geometry/Outline")
		(27 "Margin" user)
		(31 "F.CrtYd" user "Package Geometry/Place Bound Top")
		(29 "B.CrtYd" user "Package Geometry/Place Bound Bottom")
		(35 "F.Fab" user "Ref Des/Assembly Top")
		(33 "B.Fab" user "Ref Des/Assembly Bottom")
	)
	(footprint ""
		(layer "F.Cu")
		(at 111.927894 -258.880356 180)
		(property "Reference" "U26"
			(at -45.05579 -61.794136 0)
			(unlocked yes)
			(layer "F.SilkS")
			(effects
				(font
					(size 0.7874 0.5842)
					(thickness 0.1524)
				)
			)
		)
		(property "Value" ""
			(at 0 0 180)
			(layer "F.Fab")
			(effects
				(font
					(size 1.27 1.27)
				)
			)
		)
		(duplicate_pad_numbers_are_jumpers no)
		(pad "AJ14" smd circle
			(at -21.940012 -14.13002 180)
			(size 0.450088 0.450088)
			(layers "F.Cu" "F.Mask" "F.Paste")
			(net "M_H_CPU1_SA_DQ<31>")
		)
		(pad "AJ15" smd circle
			(at -20.999958 -14.13002 180)
			(size 0.450088 0.450088)
			(layers "F.Cu" "F.Mask" "F.Paste")
			(net "GND")
		)
		(pad "AJ16" smd circle
			(at -20.059904 -14.13002 180)
			(size 0.450088 0.450088)
			(layers "F.Cu" "F.Mask" "F.Paste")
			(net "M_J_CPU1_SA_CB<0>")
		)
		(pad "AJ17" smd circle
			(at -19.120104 -14.13002 180)
			(size 0.450088 0.450088)
			(layers "F.Cu" "F.Mask" "F.Paste")
			(net "M_J_CPU1_SA_DQ<31>")
		)
		(pad "AJ18" smd circle
			(at -18.18005 -14.13002 180)
			(size 0.450088 0.450088)
			(layers "F.Cu" "F.Mask" "F.Paste")
			(net "PVDDCR_SOC_P1")
		)
		(pad "AJ19" smd circle
			(at -17.239996 -14.13002 180)
			(size 0.450088 0.450088)
			(layers "F.Cu" "F.Mask" "F.Paste")
			(net "M_I_CPU1_SA_CB<0>")
		)
		(pad "AJ20" smd circle
			(at -16.299942 -14.13002 180)
			(size 0.450088 0.450088)
			(layers "F.Cu" "F.Mask" "F.Paste")
			(net "GND")
		)
		(pad "AJ21" smd circle
			(at -15.359888 -14.13002 180)
			(size 0.450088 0.450088)
			(layers "F.Cu" "F.Mask" "F.Paste")
			(net "M_I_CPU1_SA_DQ<31>")
		)
		(pad "AJ22" smd circle
			(at -14.420088 -14.13002 180)
			(size 0.450088 0.450088)
			(layers "F.Cu" "F.Mask" "F.Paste")
			(net "GND")
		)
		(pad "AJ23" smd circle
			(at -13.480034 -14.13002 180)
			(size 0.450088 0.450088)
			(layers "F.Cu" "F.Mask" "F.Paste")
			(net "GMI_CPU0_G1_CPU1_G3_TX_DN<14>")
		)
		(pad "AJ24" smd circle
			(at -12.53998 -14.13002 180)
			(size 0.450088 0.450088)
			(layers "F.Cu" "F.Mask" "F.Paste")
			(net "GMI_CPU0_G1_CPU1_G3_TX_DP<14>")
		)
		(pad "AJ25" smd circle
			(at -11.599926 -14.13002 180)
			(size 0.450088 0.450088)
			(layers "F.Cu" "F.Mask" "F.Paste")
			(net "GND")
		)
		(pad "AJ26" smd circle
			(at -10.659872 -14.13002 180)
			(size 0.450088 0.450088)
			(layers "F.Cu" "F.Mask" "F.Paste")
			(net "GMI_CPU0_G1_CPU1_G3_TX_DN<11>")
		)
		(pad "AJ27" smd circle
			(at -9.720072 -14.13002 180)
			(size 0.450088 0.450088)
			(layers "F.Cu" "F.Mask" "F.Paste")
			(net "GMI_CPU0_G1_CPU1_G3_TX_DP<11>")
		)
		(pad "AJ28" smd circle
			(at -8.780018 -14.13002 180)
			(size 0.450088 0.450088)
			(layers "F.Cu" "F.Mask" "F.Paste")
			(net "GND")
		)
		(pad "AJ29" smd circle
			(at -7.839964 -14.13002 180)
			(size 0.450088 0.450088)
			(layers "F.Cu" "F.Mask" "F.Paste")
			(net "GMI_CPU0_G1_CPU1_G3_TX_DN<8>")
		)
		(pad "AJ30" smd circle
			(at -6.89991 -14.13002 180)
			(size 0.450088 0.450088)
			(layers "F.Cu" "F.Mask" "F.Paste")
			(net "GMI_CPU0_G1_CPU1_G3_TX_DP<8>")
		)
		(pad "AJ31" smd circle
			(at -5.96011 -14.13002 180)
			(size 0.450088 0.450088)
			(layers "F.Cu" "F.Mask" "F.Paste")
			(net "GND")
		)
		(pad "AJ32" smd circle
			(at -5.020056 -14.13002 180)
			(size 0.450088 0.450088)
			(layers "F.Cu" "F.Mask" "F.Paste")
			(net "GMI_CPU0_G1_CPU1_G3_TX_DN<5>")
		)
		(pad "AJ33" smd circle
			(at -4.080002 -14.13002 180)
			(size 0.450088 0.450088)
			(layers "F.Cu" "F.Mask" "F.Paste")
			(net "GMI_CPU0_G1_CPU1_G3_TX_DP<5>")
		)
		(pad "AJ34" smd circle
			(at -3.139948 -14.13002 180)
			(size 0.450088 0.450088)
			(layers "F.Cu" "F.Mask" "F.Paste")
			(net "GND")
		)
		(pad "AJ35" smd circle
			(at -2.199894 -14.13002 180)
			(size 0.450088 0.450088)
			(layers "F.Cu" "F.Mask" "F.Paste")
			(net "GND")
		)
		(pad "AJ36" smd circle
			(at -1.260094 -14.13002 180)
			(size 0.450088 0.450088)
			(layers "F.Cu" "F.Mask" "F.Paste")
			(net "GND")
		)
		(pad "AJ40" smd circle
			(at 1.560068 -14.13002 180)
			(size 0.450088 0.450088)
			(layers "F.Cu" "F.Mask" "F.Paste")
			(net "GND")
		)
		(pad "AJ41" smd circle
			(at 2.500122 -14.13002 180)
			(size 0.450088 0.450088)
			(layers "F.Cu" "F.Mask" "F.Paste")
			(net "GND")
		)
		(pad "AJ42" smd circle
			(at 3.439922 -14.13002 180)
			(size 0.450088 0.450088)
			(layers "F.Cu" "F.Mask" "F.Paste")
			(net "GND")
		)
		(pad "AJ43" smd circle
			(at 4.379976 -14.13002 180)
			(size 0.450088 0.450088)
			(layers "F.Cu" "F.Mask" "F.Paste")
			(net "P5E_CPU1_G1_TX_DP<5>")
		)
		(pad "AJ44" smd circle
			(at 5.32003 -14.13002 180)
			(size 0.450088 0.450088)
			(layers "F.Cu" "F.Mask" "F.Paste")
			(net "P5E_CPU1_G1_TX_DN<5>")
		)
		(pad "AJ45" smd circle
			(at 6.260084 -14.13002 180)
			(size 0.450088 0.450088)
			(layers "F.Cu" "F.Mask" "F.Paste")
			(net "GND")
		)
		(pad "AJ46" smd circle
			(at 7.199884 -14.13002 180)
			(size 0.450088 0.450088)
			(layers "F.Cu" "F.Mask" "F.Paste")
			(net "P5E_CPU1_G1_TX_DP<8>")
		)
		(pad "AJ47" smd circle
			(at 8.139938 -14.13002 180)
			(size 0.450088 0.450088)
			(layers "F.Cu" "F.Mask" "F.Paste")
			(net "P5E_CPU1_G1_TX_DN<8>")
		)
		(pad "AJ48" smd circle
			(at 9.079992 -14.13002 180)
			(size 0.450088 0.450088)
			(layers "F.Cu" "F.Mask" "F.Paste")
			(net "GND")
		)
		(pad "AJ49" smd circle
			(at 10.020046 -14.13002 180)
			(size 0.450088 0.450088)
			(layers "F.Cu" "F.Mask" "F.Paste")
			(net "P5E_CPU1_G1_TX_DP<11>")
		)
		(pad "AJ50" smd circle
			(at 10.9601 -14.13002 180)
			(size 0.450088 0.450088)
			(layers "F.Cu" "F.Mask" "F.Paste")
			(net "P5E_CPU1_G1_TX_DN<11>")
		)
		(pad "AJ51" smd circle
			(at 11.8999 -14.13002 180)
			(size 0.450088 0.450088)
			(layers "F.Cu" "F.Mask" "F.Paste")
			(net "GND")
		)
		(pad "AJ52" smd circle
			(at 12.839954 -14.13002 180)
			(size 0.450088 0.450088)
			(layers "F.Cu" "F.Mask" "F.Paste")
			(net "P5E_CPU1_G1_TX_DP<14>")
		)
		(pad "AJ53" smd circle
			(at 13.780008 -14.13002 180)
			(size 0.450088 0.450088)
			(layers "F.Cu" "F.Mask" "F.Paste")
			(net "P5E_CPU1_G1_TX_DN<14>")
		)
		(pad "AJ54" smd circle
			(at 14.720062 -14.13002 180)
			(size 0.450088 0.450088)
			(layers "F.Cu" "F.Mask" "F.Paste")
			(net "GND")
		)
		(pad "AJ55" smd circle
			(at 15.660116 -14.13002 180)
			(size 0.450088 0.450088)
			(layers "F.Cu" "F.Mask" "F.Paste")
			(net "M_C_CPU1_SA_DQ<31>")
		)
		(pad "AJ56" smd circle
			(at 16.599916 -14.13002 180)
			(size 0.450088 0.450088)
			(layers "F.Cu" "F.Mask" "F.Paste")
			(net "GND")
		)
		(pad "AJ57" smd circle
			(at 17.53997 -14.13002 180)
			(size 0.450088 0.450088)
			(layers "F.Cu" "F.Mask" "F.Paste")
			(net "M_C_CPU1_SA_CB<0>")
		)
		(pad "AJ58" smd circle
			(at 18.480024 -14.13002 180)
			(size 0.450088 0.450088)
			(layers "F.Cu" "F.Mask" "F.Paste")
			(net "PVDDIO_P1")
		)
		(pad "AJ59" smd circle
			(at 19.420078 -14.13002 180)
			(size 0.450088 0.450088)
			(layers "F.Cu" "F.Mask" "F.Paste")
			(net "M_D_CPU1_SA_DQ<31>")
		)
		(pad "AJ60" smd circle
			(at 20.359878 -14.13002 180)
			(size 0.450088 0.450088)
			(layers "F.Cu" "F.Mask" "F.Paste")
			(net "M_D_CPU1_SA_CB<0>")
		)
		(pad "AJ61" smd circle
			(at 21.299932 -14.13002 180)
			(size 0.450088 0.450088)
			(layers "F.Cu" "F.Mask" "F.Paste")
			(net "GND")
		)
		(pad "AJ62" smd circle
			(at 22.239986 -14.13002 180)
			(size 0.450088 0.450088)
			(layers "F.Cu" "F.Mask" "F.Paste")
			(net "M_B_CPU1_SA_DQ<31>")
		)
		(pad "AJ63" smd circle
			(at 23.18004 -14.13002 180)
			(size 0.450088 0.450088)
			(layers "F.Cu" "F.Mask" "F.Paste")
			(net "GND")
		)
		(pad "AJ64" smd circle
			(at 24.120094 -14.13002 180)
			(size 0.450088 0.450088)
			(layers "F.Cu" "F.Mask" "F.Paste")
			(net "M_B_CPU1_SA_CB<0>")
		)
		(pad "AJ65" smd circle
			(at 25.059894 -14.13002 180)
			(size 0.450088 0.450088)
			(layers "F.Cu" "F.Mask" "F.Paste")
			(net "PVDDIO_P1")
		)
		(pad "AJ66" smd circle
			(at 25.999948 -14.13002 180)
			(size 0.450088 0.450088)
			(layers "F.Cu" "F.Mask" "F.Paste")
			(net "M_F_CPU1_SA_DQ<31>")
		)
		(pad "AJ67" smd circle
			(at 26.940002 -14.13002 180)
			(size 0.450088 0.450088)
			(layers "F.Cu" "F.Mask" "F.Paste")
			(net "M_F_CPU1_SA_CB<0>")
		)
		(pad "AJ68" smd circle
			(at 27.880056 -14.13002 180)
			(size 0.450088 0.450088)
			(layers "F.Cu" "F.Mask" "F.Paste")
			(net "GND")
		)
		(pad "AJ69" smd circle
			(at 28.82011 -14.13002 180)
			(size 0.450088 0.450088)
			(layers "F.Cu" "F.Mask" "F.Paste")
			(net "M_E_CPU1_SA_DQ<31>")
		)
		(pad "AJ70" smd circle
			(at 29.75991 -14.13002 180)
			(size 0.450088 0.450088)
			(layers "F.Cu" "F.Mask" "F.Paste")
			(net "GND")
		)
		(pad "AJ71" smd circle
			(at 30.699964 -14.13002 180)
			(size 0.450088 0.450088)
			(layers "F.Cu" "F.Mask" "F.Paste")
			(net "M_E_CPU1_SA_CB<0>")
		)
		(pad "AJ72" smd circle
			(at 31.640018 -14.13002 180)
			(size 0.450088 0.450088)
			(layers "F.Cu" "F.Mask" "F.Paste")
			(net "PVDDIO_P1")
		)
		(pad "AJ73" smd circle
			(at 32.580072 -14.13002 180)
			(size 0.450088 0.450088)
			(layers "F.Cu" "F.Mask" "F.Paste")
			(net "M_A_CPU1_SA_DQ<31>")
		)
		(pad "AJ74" smd circle
			(at 33.519872 -14.13002 180)
			(size 0.450088 0.450088)
			(layers "F.Cu" "F.Mask" "F.Paste")
			(net "M_A_CPU1_SA_CB<0>")
		)
		(pad "AJ75" smd circle
			(at 34.459926 -14.13002 180)
			(size 0.450088 0.450088)
			(layers "F.Cu" "F.Mask" "F.Paste")
			(net "GND")
		)
		(pad "AK2" smd circle
			(at -33.690052 -13.320014 180)
			(size 0.450088 0.450088)
			(layers "F.Cu" "F.Mask" "F.Paste")
			(net "M_G_CPU1_SA_CB<2>")
		)
		(pad "AK3" smd circle
			(at -32.749998 -13.320014 180)
			(size 0.450088 0.450088)
			(layers "F.Cu" "F.Mask" "F.Paste")
			(net "GND")
		)
		(pad "AK4" smd circle
			(at -31.809944 -13.320014 180)
			(size 0.450088 0.450088)
			(layers "F.Cu" "F.Mask" "F.Paste")
			(net "M_G_CPU1_SA_CB<1>")
		)
		(pad "AK5" smd circle
			(at -30.86989 -13.320014 180)
			(size 0.450088 0.450088)
			(layers "F.Cu" "F.Mask" "F.Paste")
			(net "GND")
		)
		(pad "AK6" smd circle
			(at -29.93009 -13.320014 180)
			(size 0.450088 0.450088)
			(layers "F.Cu" "F.Mask" "F.Paste")
			(net "M_K_CPU1_SA_CB<2>")
		)
		(pad "AK7" smd circle
			(at -28.990036 -13.320014 180)
			(size 0.450088 0.450088)
			(layers "F.Cu" "F.Mask" "F.Paste")
			(net "M_K_CPU1_SA_CB<1>")
		)
		(pad "AK8" smd circle
			(at -28.049982 -13.320014 180)
			(size 0.450088 0.450088)
			(layers "F.Cu" "F.Mask" "F.Paste")
			(net "GND")
		)
		(pad "AK9" smd circle
			(at -27.109928 -13.320014 180)
			(size 0.450088 0.450088)
			(layers "F.Cu" "F.Mask" "F.Paste")
			(net "M_L_CPU1_SA_CB<2>")
		)
		(pad "AK10" smd circle
			(at -26.170128 -13.320014 180)
			(size 0.450088 0.450088)
			(layers "F.Cu" "F.Mask" "F.Paste")
			(net "GND")
		)
		(pad "AK11" smd circle
			(at -25.230074 -13.320014 180)
			(size 0.450088 0.450088)
			(layers "F.Cu" "F.Mask" "F.Paste")
			(net "M_L_CPU1_SA_CB<1>")
		)
		(pad "AK12" smd circle
			(at -24.29002 -13.320014 180)
			(size 0.450088 0.450088)
			(layers "F.Cu" "F.Mask" "F.Paste")
			(net "GND")
		)
		(pad "AK13" smd circle
			(at -23.349966 -13.320014 180)
			(size 0.450088 0.450088)
			(layers "F.Cu" "F.Mask" "F.Paste")
			(net "M_H_CPU1_SA_CB<2>")
		)
		(pad "AK14" smd circle
			(at -22.409912 -13.320014 180)
			(size 0.450088 0.450088)
			(layers "F.Cu" "F.Mask" "F.Paste")
			(net "M_H_CPU1_SA_CB<1>")
		)
		(pad "AK15" smd circle
			(at -21.470112 -13.320014 180)
			(size 0.450088 0.450088)
			(layers "F.Cu" "F.Mask" "F.Paste")
			(net "GND")
		)
		(pad "AK16" smd circle
			(at -20.530058 -13.320014 180)
			(size 0.450088 0.450088)
			(layers "F.Cu" "F.Mask" "F.Paste")
			(net "M_J_CPU1_SA_CB<2>")
		)
		(pad "AK17" smd circle
			(at -19.590004 -13.320014 180)
			(size 0.450088 0.450088)
			(layers "F.Cu" "F.Mask" "F.Paste")
			(net "GND")
		)
		(pad "AK18" smd circle
			(at -18.64995 -13.320014 180)
			(size 0.450088 0.450088)
			(layers "F.Cu" "F.Mask" "F.Paste")
			(net "M_J_CPU1_SA_CB<1>")
		)
		(pad "AK19" smd circle
			(at -17.709896 -13.320014 180)
			(size 0.450088 0.450088)
			(layers "F.Cu" "F.Mask" "F.Paste")
			(net "GND")
		)
		(pad "AK20" smd circle
			(at -16.770096 -13.320014 180)
			(size 0.450088 0.450088)
			(layers "F.Cu" "F.Mask" "F.Paste")
			(net "M_I_CPU1_SA_CB<2>")
		)
		(pad "AK21" smd circle
			(at -15.830042 -13.320014 180)
			(size 0.450088 0.450088)
			(layers "F.Cu" "F.Mask" "F.Paste")
			(net "M_I_CPU1_SA_CB<1>")
		)
		(pad "AK22" smd circle
			(at -14.889988 -13.320014 180)
			(size 0.450088 0.450088)
			(layers "F.Cu" "F.Mask" "F.Paste")
			(net "GND")
		)
		(pad "AK23" smd circle
			(at -13.949934 -13.320014 180)
			(size 0.450088 0.450088)
			(layers "F.Cu" "F.Mask" "F.Paste")
			(net "PVDDCR_CPU0_P1")
		)
		(pad "AK24" smd circle
			(at -13.00988 -13.320014 180)
			(size 0.450088 0.450088)
			(layers "F.Cu" "F.Mask" "F.Paste")
			(net "PVDDCR_CPU0_P1")
		)
		(pad "AK25" smd circle
			(at -12.07008 -13.320014 180)
			(size 0.450088 0.450088)
			(layers "F.Cu" "F.Mask" "F.Paste")
			(net "GND")
		)
		(pad "AK26" smd circle
			(at -11.130026 -13.320014 180)
			(size 0.450088 0.450088)
			(layers "F.Cu" "F.Mask" "F.Paste")
			(net "PVDDCR_CPU0_P1")
		)
		(pad "AK27" smd circle
			(at -10.189972 -13.320014 180)
			(size 0.450088 0.450088)
			(layers "F.Cu" "F.Mask" "F.Paste")
			(net "PVDDCR_CPU0_P1")
		)
		(pad "AK28" smd circle
			(at -9.249918 -13.320014 180)
			(size 0.450088 0.450088)
			(layers "F.Cu" "F.Mask" "F.Paste")
			(net "GND")
		)
		(pad "AK29" smd circle
			(at -8.310118 -13.320014 180)
			(size 0.450088 0.450088)
			(layers "F.Cu" "F.Mask" "F.Paste")
			(net "PVDDCR_CPU0_P1")
		)
		(pad "AK30" smd circle
			(at -7.370064 -13.320014 180)
			(size 0.450088 0.450088)
			(layers "F.Cu" "F.Mask" "F.Paste")
			(net "PVDDCR_CPU0_P1")
		)
		(pad "AK31" smd circle
			(at -6.43001 -13.320014 180)
			(size 0.450088 0.450088)
			(layers "F.Cu" "F.Mask" "F.Paste")
			(net "GND")
		)
		(pad "AK32" smd circle
			(at -5.489956 -13.320014 180)
			(size 0.450088 0.450088)
			(layers "F.Cu" "F.Mask" "F.Paste")
			(net "PVDDCR_CPU0_P1")
		)
		(pad "AK33" smd circle
			(at -4.549902 -13.320014 180)
			(size 0.450088 0.450088)
			(layers "F.Cu" "F.Mask" "F.Paste")
			(net "PVDDCR_CPU0_P1")
		)
		(pad "AK34" smd circle
			(at -3.610102 -13.320014 180)
			(size 0.450088 0.450088)
			(layers "F.Cu" "F.Mask" "F.Paste")
			(net "GND")
		)
		(pad "AK35" smd circle
			(at -2.670048 -13.320014 180)
			(size 0.450088 0.450088)
			(layers "F.Cu" "F.Mask" "F.Paste")
			(net "GMI_CPU0_G1_CPU1_G3_TX_DN<3>")
		)
		(pad "AK36" smd circle
			(at -1.729994 -13.320014 180)
			(size 0.450088 0.450088)
			(layers "F.Cu" "F.Mask" "F.Paste")
			(net "GMI_CPU0_G1_CPU1_G3_TX_DP<3>")
		)
		(pad "AK37" smd circle
			(at -0.78994 -13.320014 180)
			(size 0.450088 0.450088)
			(layers "F.Cu" "F.Mask" "F.Paste")
			(net "GND")
		)
		(pad "AK39" smd circle
			(at 1.089914 -13.320014 180)
			(size 0.450088 0.450088)
			(layers "F.Cu" "F.Mask" "F.Paste")
			(net "GND")
		)
		(pad "AK40" smd circle
			(at 2.029968 -13.320014 180)
			(size 0.450088 0.450088)
			(layers "F.Cu" "F.Mask" "F.Paste")
			(net "P5E_CPU1_G1_TX_DP<3>")
		)
		(pad "AK41" smd circle
			(at 2.970022 -13.320014 180)
			(size 0.450088 0.450088)
			(layers "F.Cu" "F.Mask" "F.Paste")
			(net "P5E_CPU1_G1_TX_DN<3>")
		)
		(pad "AK42" smd circle
			(at 3.910076 -13.320014 180)
			(size 0.450088 0.450088)
			(layers "F.Cu" "F.Mask" "F.Paste")
			(net "GND")
		)
		(pad "AK43" smd circle
			(at 4.849876 -13.320014 180)
			(size 0.450088 0.450088)
			(layers "F.Cu" "F.Mask" "F.Paste")
			(net "PVDDCR_CPU0_P1")
		)
		(pad "AK44" smd circle
			(at 5.78993 -13.320014 180)
			(size 0.450088 0.450088)
			(layers "F.Cu" "F.Mask" "F.Paste")
			(net "PVDDCR_CPU0_P1")
		)
		(pad "AK45" smd circle
			(at 6.729984 -13.320014 180)
			(size 0.450088 0.450088)
			(layers "F.Cu" "F.Mask" "F.Paste")
			(net "GND")
		)
		(pad "AK46" smd circle
			(at 7.670038 -13.320014 180)
			(size 0.450088 0.450088)
			(layers "F.Cu" "F.Mask" "F.Paste")
			(net "PVDDCR_CPU0_P1")
		)
		(pad "AK47" smd circle
			(at 8.610092 -13.320014 180)
			(size 0.450088 0.450088)
			(layers "F.Cu" "F.Mask" "F.Paste")
			(net "PVDDCR_CPU0_P1")
		)
		(pad "AK48" smd circle
			(at 9.549892 -13.320014 180)
			(size 0.450088 0.450088)
			(layers "F.Cu" "F.Mask" "F.Paste")
			(net "GND")
		)
		(pad "AK49" smd circle
			(at 10.489946 -13.320014 180)
			(size 0.450088 0.450088)
			(layers "F.Cu" "F.Mask" "F.Paste")
			(net "PVDDCR_CPU0_P1")
		)
		(pad "AK50" smd circle
			(at 11.43 -13.320014 180)
			(size 0.450088 0.450088)
			(layers "F.Cu" "F.Mask" "F.Paste")
			(net "PVDDCR_CPU0_P1")
		)
		(pad "AK51" smd circle
			(at 12.370054 -13.320014 180)
			(size 0.450088 0.450088)
			(layers "F.Cu" "F.Mask" "F.Paste")
			(net "GND")
		)
	)
)
